(kicad_pcb
	(version 20241229)
	(generator "pcbnew")
	(generator_version "9.0")
	(general
		(thickness 1.599998)
		(legacy_teardrops no)
	)
	(paper "A4")
	(title_block
		(date "2023-02-12")
		(rev "1.1.5")
		(comment 9 "footprints 10-16 of 473")
	)
	(layers
		(0 "F.Cu" signal)
		(4 "In1.Cu" power "In1.GND")
		(6 "In2.Cu" signal)
		(8 "In3.Cu" power "In3.GND")
		(10 "In4.Cu" power "In4.VCC")
		(12 "In5.Cu" signal)
		(14 "In6.Cu" power "In6.VCC")
		(2 "B.Cu" signal)
		(9 "F.Adhes" user "F.Adhesive")
		(11 "B.Adhes" user "B.Adhesive")
		(13 "F.Paste" user)
		(15 "B.Paste" user)
		(5 "F.SilkS" user "F.Silkscreen")
		(7 "B.SilkS" user "B.Silkscreen")
		(1 "F.Mask" user)
		(3 "B.Mask" user)
		(17 "Dwgs.User" user "User.Drawings")
		(19 "Cmts.User" user "User.Comments")
		(21 "Eco1.User" user "User.Eco1")
		(23 "Eco2.User" user "User.Eco2")
		(25 "Edge.Cuts" user)
		(27 "Margin" user)
		(31 "F.CrtYd" user "F.Courtyard")
		(29 "B.CrtYd" user "B.Courtyard")
		(35 "F.Fab" user)
		(33 "B.Fab" user)
	)
	(footprint "antmicro-footprints:SOT-723"
		(layer "F.Cu")
		(at 135.882328 125.941157 90)
		(property "Reference" "D4"
			(at -0.758843 1.717672 90)
			(layer "F.SilkS")
			(effects
				(font
					(size 0.7 0.7)
					(thickness 0.15)
				)
				(justify left bottom)
			)
		)
		(property "Value" "TPD2E009_SOT-9X3"
			(at 0 1.7 90)
			(layer "F.Fab")
			(effects
				(font
					(size 0.7 0.7)
					(thickness 0.15)
				)
				(justify left bottom)
			)
		)
		(property "Description" "2-Channel ESD Solution for High-Speed (6-Gbps) Differential Interface"
			(at 0 0 90)
			(layer "F.Fab")
			(hide yes)
			(effects
				(font
					(size 1.27 1.27)
					(thickness 0.15)
				)
			)
		)
		(property "Author" "Antmicro"
			(at 261.823485 -9.941171 0)
			(layer "F.Fab")
			(hide yes)
			(effects
				(font
					(size 1 1)
					(thickness 0.15)
				)
			)
		)
		(property "License" "Apache-2.0"
			(at 261.823485 -9.941171 0)
			(layer "F.Fab")
			(hide yes)
			(effects
				(font
					(size 1 1)
					(thickness 0.15)
				)
			)
		)
		(property "MPN" "TPD2E009DRTR"
			(at 261.823485 -9.941171 0)
			(layer "F.Fab")
			(hide yes)
			(effects
				(font
					(size 1 1)
					(thickness 0.15)
				)
			)
		)
		(property "Manufacturer" "Texas Instruments"
			(at 261.823485 -9.941171 0)
			(layer "F.Fab")
			(hide yes)
			(effects
				(font
					(size 1 1)
					(thickness 0.15)
				)
			)
		)
		(sheetname "Interfaces")
		(sheetfile "interfaces.kicad_sch")
		(attr smd)
		(fp_line
			(start 0.43 -0.63)
			(end -0.2175 -0.63)
			(stroke
				(width 0.15)
				(type solid)
			)
			(layer "F.SilkS")
		)
		(fp_line
			(start 0.43 -0.23)
			(end 0.43 -0.63)
			(stroke
				(width 0.15)
				(type solid)
			)
			(layer "F.SilkS")
		)
		(fp_line
			(start -0.43 -0.1375)
			(end -0.43 0.1375)
			(stroke
				(width 0.15)
				(type solid)
			)
			(layer "F.SilkS")
		)
		(fp_line
			(start 0.43 0.23)
			(end 0.43 0.63)
			(stroke
				(width 0.15)
				(type solid)
			)
			(layer "F.SilkS")
		)
		(fp_line
			(start 0.43 0.63)
			(end -0.22 0.63)
			(stroke
				(width 0.15)
				(type solid)
			)
			(layer "F.SilkS")
		)
		(fp_rect
			(start -0.83 -0.83)
			(end 0.83 0.83)
			(stroke
				(width 0.05)
				(type solid)
			)
			(fill no)
			(layer "F.CrtYd")
		)
		(fp_line
			(start -0.09 -0.53)
			(end -0.43 -0.19)
			(stroke
				(width 0.15)
				(type solid)
			)
			(layer "F.Fab")
		)
		(fp_line
			(start 0.424 -0.528)
			(end 0.424 0.524)
			(stroke
				(width 0.15)
				(type solid)
			)
			(layer "F.Fab")
		)
		(fp_line
			(start 0.424 0.524)
			(end -0.424 0.524)
			(stroke
				(width 0.15)
				(type solid)
			)
			(layer "F.Fab")
		)
		(fp_rect
			(start 0.424 0.524)
			(end -0.43 -0.528)
			(stroke
				(width 0.15)
				(type solid)
			)
			(fill no)
			(layer "F.Fab")
		)
		(pad "1" smd rect
			(at -0.501 -0.401)
			(size 0.3 0.4)
			(layers "F.Cu" "F.Mask" "F.Paste")
			(net 7 "DBG_USB_N")
			(pinfunction "1")
			(pintype "passive")
		)
		(pad "2" smd rect
			(at -0.501 0.399)
			(size 0.3 0.4)
			(layers "F.Cu" "F.Mask" "F.Paste")
			(net 6 "DBG_USB_P")
			(pinfunction "2")
			(pintype "passive")
		)
		(pad "3" smd rect
			(at 0.499 -0.001)
			(size 0.3 0.4)
			(layers "F.Cu" "F.Mask" "F.Paste")
			(net 5 "GND")
			(pinfunction "3")
			(pintype "passive")
		)
	)
	(footprint "antmicro-footprints:FB_0603_1608Metric"
		(layer "F.Cu")
		(at 133.292 126.508 180)
		(property "Reference" "FB3"
			(at 0.992 0.708 180)
			(layer "F.SilkS")
			(effects
				(font
					(size 0.7 0.7)
					(thickness 0.15)
				)
				(justify left bottom)
			)
		)
		(property "Value" "FB_600Z_0.5A_0603"
			(at 0 1.5 180)
			(layer "F.Fab")
			(effects
				(font
					(size 0.7 0.7)
					(thickness 0.15)
				)
				(justify left bottom)
			)
		)
		(property "Description" "Ferrite Beads WE-TMSB Suppression 240Ohm 200mA "
			(at 0 0 180)
			(layer "F.Fab")
			(hide yes)
			(effects
				(font
					(size 1.27 1.27)
					(thickness 0.15)
				)
			)
		)
		(property "Author" "Antmicro"
			(at 266.584 253.016 0)
			(layer "F.Fab")
			(hide yes)
			(effects
				(font
					(size 1 1)
					(thickness 0.15)
				)
			)
		)
		(property "License" "Apache-2.0"
			(at 266.584 253.016 0)
			(layer "F.Fab")
			(hide yes)
			(effects
				(font
					(size 1 1)
					(thickness 0.15)
				)
			)
		)
		(property "MPN" "BLM18AG601SN1D"
			(at 266.584 253.016 0)
			(layer "F.Fab")
			(hide yes)
			(effects
				(font
					(size 1 1)
					(thickness 0.15)
				)
			)
		)
		(property "Manufacturer" "Murata"
			(at 266.584 253.016 0)
			(layer "F.Fab")
			(hide yes)
			(effects
				(font
					(size 1 1)
					(thickness 0.15)
				)
			)
		)
		(sheetname "Interfaces")
		(sheetfile "interfaces.kicad_sch")
		(attr smd)
		(fp_line
			(start -0.196 0.406)
			(end 0.193 0.406)
			(stroke
				(width 0.15)
				(type solid)
			)
			(layer "F.SilkS")
		)
		(fp_line
			(start -0.196 -0.408)
			(end 0.193 -0.408)
			(stroke
				(width 0.15)
				(type solid)
			)
			(layer "F.SilkS")
		)
		(fp_rect
			(start -1.3 -0.6)
			(end 1.3 0.6)
			(stroke
				(width 0.05)
				(type solid)
			)
			(fill no)
			(layer "F.CrtYd")
		)
		(fp_line
			(start 0.8 0.406)
			(end -0.803 0.406)
			(stroke
				(width 0.15)
				(type solid)
			)
			(layer "F.Fab")
		)
		(fp_line
			(start 0.8 -0.408)
			(end 0.8 0.406)
			(stroke
				(width 0.15)
				(type solid)
			)
			(layer "F.Fab")
		)
		(fp_line
			(start 0.8 -0.408)
			(end -0.803 -0.408)
			(stroke
				(width 0.15)
				(type solid)
			)
			(layer "F.Fab")
		)
		(fp_line
			(start -0.803 0.406)
			(end -0.803 -0.408)
			(stroke
				(width 0.15)
				(type solid)
			)
			(layer "F.Fab")
		)
		(pad "1" smd roundrect
			(at -0.891 0 180)
			(size 0.762 1.09)
			(layers "F.Cu" "F.Mask" "F.Paste")
			(roundrect_rratio 0.15)
			(net 5 "GND")
			(pintype "passive")
		)
		(pad "2" smd roundrect
			(at 0.888 0 180)
			(size 0.762 1.09)
			(layers "F.Cu" "F.Mask" "F.Paste")
			(roundrect_rratio 0.15)
			(net 74 "Net-(J1-SHIELD)")
			(pintype "passive")
		)
	)
	(footprint "antmicro-footprints:R_0402_1005Metric"
		(layer "F.Cu")
		(at 148.051328 107.746157)
		(descr "Resistor SMD 0402")
		(tags "resistor SMD 0402")
		(property "Reference" "R17"
			(at 0.763672 0.428843 0)
			(layer "F.SilkS")
			(effects
				(font
					(size 0.7 0.7)
					(thickness 0.15)
				)
				(justify left bottom)
			)
		)
		(property "Value" "R_22R_0402"
			(at 0 1.4 0)
			(layer "F.Fab")
			(effects
				(font
					(size 0.7 0.7)
					(thickness 0.15)
				)
				(justify left bottom)
			)
		)
		(property "Description" "22R resistor in 0402 package with 1% tolerance"
			(at 0 0 0)
			(layer "F.Fab")
			(hide yes)
			(effects
				(font
					(size 1.27 1.27)
					(thickness 0.15)
				)
			)
		)
		(property "Author" "Antmicro"
			(at 0 0 0)
			(layer "F.Fab")
			(hide yes)
			(effects
				(font
					(size 1 1)
					(thickness 0.15)
				)
			)
		)
		(property "License" "Apache-2.0"
			(at 0 0 0)
			(layer "F.Fab")
			(hide yes)
			(effects
				(font
					(size 1 1)
					(thickness 0.15)
				)
			)
		)
		(property "MPN" "CR0402-FX-22R0GLF"
			(at 0 0 0)
			(layer "F.Fab")
			(hide yes)
			(effects
				(font
					(size 1 1)
					(thickness 0.15)
				)
			)
		)
		(property "Manufacturer" "Bourns"
			(at 0 0 0)
			(layer "F.Fab")
			(hide yes)
			(effects
				(font
					(size 1 1)
					(thickness 0.15)
				)
			)
		)
		(property "Tolerance" "1%"
			(at 0 0 0)
			(layer "F.Fab")
			(hide yes)
			(effects
				(font
					(size 1 1)
					(thickness 0.15)
				)
			)
		)
		(property "Val" "22R"
			(at 0 0 0)
			(layer "F.Fab")
			(hide yes)
			(effects
				(font
					(size 1 1)
					(thickness 0.15)
				)
			)
		)
		(sheetname "Interfaces")
		(sheetfile "interfaces.kicad_sch")
		(attr smd)
		(fp_rect
			(start -0.93 -0.47)
			(end 0.93 0.47)
			(stroke
				(width 0.05)
				(type solid)
			)
			(fill no)
			(layer "F.CrtYd")
		)
		(fp_rect
			(start -0.5 -0.25)
			(end 0.5 0.25)
			(stroke
				(width 0.15)
				(type solid)
			)
			(fill no)
			(layer "F.Fab")
		)
		(pad "1" smd roundrect
			(at -0.485 0)
			(size 0.59 0.64)
			(layers "F.Cu" "F.Mask" "F.Paste")
			(roundrect_rratio 0.25)
			(net 246 "Net-(U4-BDBUS0)")
			(pintype "passive")
		)
		(pad "2" smd roundrect
			(at 0.485 0)
			(size 0.59 0.64)
			(layers "F.Cu" "F.Mask" "F.Paste")
			(roundrect_rratio 0.25)
			(net 442 "AUX_JTAG_TCK")
			(pintype "passive")
		)
	)
	(footprint "antmicro-footprints:R_0402_1005Metric"
		(layer "F.Cu")
		(at 148.036328 106.621157)
		(descr "Resistor SMD 0402")
		(tags "resistor SMD 0402")
		(property "Reference" "R18"
			(at 0.763672 0.428843 0)
			(layer "F.SilkS")
			(effects
				(font
					(size 0.7 0.7)
					(thickness 0.15)
				)
				(justify left bottom)
			)
		)
		(property "Value" "R_22R_0402"
			(at 0 1.4 0)
			(layer "F.Fab")
			(effects
				(font
					(size 0.7 0.7)
					(thickness 0.15)
				)
				(justify left bottom)
			)
		)
		(property "Description" "22R resistor in 0402 package with 1% tolerance"
			(at 0 0 0)
			(layer "F.Fab")
			(hide yes)
			(effects
				(font
					(size 1.27 1.27)
					(thickness 0.15)
				)
			)
		)
		(property "Author" "Antmicro"
			(at 0 0 0)
			(layer "F.Fab")
			(hide yes)
			(effects
				(font
					(size 1 1)
					(thickness 0.15)
				)
			)
		)
		(property "License" "Apache-2.0"
			(at 0 0 0)
			(layer "F.Fab")
			(hide yes)
			(effects
				(font
					(size 1 1)
					(thickness 0.15)
				)
			)
		)
		(property "MPN" "CR0402-FX-22R0GLF"
			(at 0 0 0)
			(layer "F.Fab")
			(hide yes)
			(effects
				(font
					(size 1 1)
					(thickness 0.15)
				)
			)
		)
		(property "Manufacturer" "Bourns"
			(at 0 0 0)
			(layer "F.Fab")
			(hide yes)
			(effects
				(font
					(size 1 1)
					(thickness 0.15)
				)
			)
		)
		(property "Tolerance" "1%"
			(at 0 0 0)
			(layer "F.Fab")
			(hide yes)
			(effects
				(font
					(size 1 1)
					(thickness 0.15)
				)
			)
		)
		(property "Val" "22R"
			(at 0 0 0)
			(layer "F.Fab")
			(hide yes)
			(effects
				(font
					(size 1 1)
					(thickness 0.15)
				)
			)
		)
		(sheetname "Interfaces")
		(sheetfile "interfaces.kicad_sch")
		(attr smd)
		(fp_rect
			(start -0.93 -0.47)
			(end 0.93 0.47)
			(stroke
				(width 0.05)
				(type solid)
			)
			(fill no)
			(layer "F.CrtYd")
		)
		(fp_rect
			(start -0.5 -0.25)
			(end 0.5 0.25)
			(stroke
				(width 0.15)
				(type solid)
			)
			(fill no)
			(layer "F.Fab")
		)
		(pad "1" smd roundrect
			(at -0.485 0)
			(size 0.59 0.64)
			(layers "F.Cu" "F.Mask" "F.Paste")
			(roundrect_rratio 0.25)
			(net 247 "Net-(U4-BDBUS1)")
			(pintype "passive")
		)
		(pad "2" smd roundrect
			(at 0.485 0)
			(size 0.59 0.64)
			(layers "F.Cu" "F.Mask" "F.Paste")
			(roundrect_rratio 0.25)
			(net 444 "AUX_JTAG_TDI")
			(pintype "passive")
		)
	)
	(footprint "antmicro-footprints:R_0402_1005Metric"
		(layer "F.Cu")
		(at 148.036328 105.496157)
		(descr "Resistor SMD 0402")
		(tags "resistor SMD 0402")
		(property "Reference" "R19"
			(at 0.763672 0.428843 0)
			(layer "F.SilkS")
			(effects
				(font
					(size 0.7 0.7)
					(thickness 0.15)
				)
				(justify left bottom)
			)
		)
		(property "Value" "R_22R_0402"
			(at 0 1.4 0)
			(layer "F.Fab")
			(effects
				(font
					(size 0.7 0.7)
					(thickness 0.15)
				)
				(justify left bottom)
			)
		)
		(property "Description" "22R resistor in 0402 package with 1% tolerance"
			(at 0 0 0)
			(layer "F.Fab")
			(hide yes)
			(effects
				(font
					(size 1.27 1.27)
					(thickness 0.15)
				)
			)
		)
		(property "Author" "Antmicro"
			(at 0 0 0)
			(layer "F.Fab")
			(hide yes)
			(effects
				(font
					(size 1 1)
					(thickness 0.15)
				)
			)
		)
		(property "License" "Apache-2.0"
			(at 0 0 0)
			(layer "F.Fab")
			(hide yes)
			(effects
				(font
					(size 1 1)
					(thickness 0.15)
				)
			)
		)
		(property "MPN" "CR0402-FX-22R0GLF"
			(at 0 0 0)
			(layer "F.Fab")
			(hide yes)
			(effects
				(font
					(size 1 1)
					(thickness 0.15)
				)
			)
		)
		(property "Manufacturer" "Bourns"
			(at 0 0 0)
			(layer "F.Fab")
			(hide yes)
			(effects
				(font
					(size 1 1)
					(thickness 0.15)
				)
			)
		)
		(property "Tolerance" "1%"
			(at 0 0 0)
			(layer "F.Fab")
			(hide yes)
			(effects
				(font
					(size 1 1)
					(thickness 0.15)
				)
			)
		)
		(property "Val" "22R"
			(at 0 0 0)
			(layer "F.Fab")
			(hide yes)
			(effects
				(font
					(size 1 1)
					(thickness 0.15)
				)
			)
		)
		(sheetname "Interfaces")
		(sheetfile "interfaces.kicad_sch")
		(attr smd)
		(fp_rect
			(start -0.93 -0.47)
			(end 0.93 0.47)
			(stroke
				(width 0.05)
				(type solid)
			)
			(fill no)
			(layer "F.CrtYd")
		)
		(fp_rect
			(start -0.5 -0.25)
			(end 0.5 0.25)
			(stroke
				(width 0.15)
				(type solid)
			)
			(fill no)
			(layer "F.Fab")
		)
		(pad "1" smd roundrect
			(at -0.485 0)
			(size 0.59 0.64)
			(layers "F.Cu" "F.Mask" "F.Paste")
			(roundrect_rratio 0.25)
			(net 248 "Net-(U4-BDBUS2)")
			(pintype "passive")
		)
		(pad "2" smd roundrect
			(at 0.485 0)
			(size 0.59 0.64)
			(layers "F.Cu" "F.Mask" "F.Paste")
			(roundrect_rratio 0.25)
			(net 464 "AUX_JTAG_TDO")
			(pintype "passive")
		)
	)
	(footprint "antmicro-footprints:R_0402_1005Metric"
		(layer "F.Cu")
		(at 148.036328 102.121157)
		(descr "Resistor SMD 0402")
		(tags "resistor SMD 0402")
		(property "Reference" "R21"
			(at 0.763672 0.378843 0)
			(layer "F.SilkS")
			(effects
				(font
					(size 0.7 0.7)
					(thickness 0.15)
				)
				(justify left bottom)
			)
		)
		(property "Value" "R_22R_0402"
			(at 0 1.4 0)
			(layer "F.Fab")
			(effects
				(font
					(size 0.7 0.7)
					(thickness 0.15)
				)
				(justify left bottom)
			)
		)
		(property "Description" "22R resistor in 0402 package with 1% tolerance"
			(at 0 0 0)
			(layer "F.Fab")
			(hide yes)
			(effects
				(font
					(size 1.27 1.27)
					(thickness 0.15)
				)
			)
		)
		(property "Author" "Antmicro"
			(at 0 0 0)
			(layer "F.Fab")
			(hide yes)
			(effects
				(font
					(size 1 1)
					(thickness 0.15)
				)
			)
		)
		(property "License" "Apache-2.0"
			(at 0 0 0)
			(layer "F.Fab")
			(hide yes)
			(effects
				(font
					(size 1 1)
					(thickness 0.15)
				)
			)
		)
		(property "MPN" "CR0402-FX-22R0GLF"
			(at 0 0 0)
			(layer "F.Fab")
			(hide yes)
			(effects
				(font
					(size 1 1)
					(thickness 0.15)
				)
			)
		)
		(property "Manufacturer" "Bourns"
			(at 0 0 0)
			(layer "F.Fab")
			(hide yes)
			(effects
				(font
					(size 1 1)
					(thickness 0.15)
				)
			)
		)
		(property "Tolerance" "1%"
			(at 0 0 0)
			(layer "F.Fab")
			(hide yes)
			(effects
				(font
					(size 1 1)
					(thickness 0.15)
				)
			)
		)
		(property "Val" "22R"
			(at 0 0 0)
			(layer "F.Fab")
			(hide yes)
			(effects
				(font
					(size 1 1)
					(thickness 0.15)
				)
			)
		)
		(sheetname "Interfaces")
		(sheetfile "interfaces.kicad_sch")
		(attr smd)
		(fp_rect
			(start -0.93 -0.47)
			(end 0.93 0.47)
			(stroke
				(width 0.05)
				(type solid)
			)
			(fill no)
			(layer "F.CrtYd")
		)
		(fp_rect
			(start -0.5 -0.25)
			(end 0.5 0.25)
			(stroke
				(width 0.15)
				(type solid)
			)
			(fill no)
			(layer "F.Fab")
		)
		(pad "1" smd roundrect
			(at -0.485 0)
			(size 0.59 0.64)
			(layers "F.Cu" "F.Mask" "F.Paste")
			(roundrect_rratio 0.25)
			(net 250 "Net-(U4-BDBUS5)")
			(pintype "passive")
		)
		(pad "2" smd roundrect
			(at 0.485 0)
			(size 0.59 0.64)
			(layers "F.Cu" "F.Mask" "F.Paste")
			(roundrect_rratio 0.25)
			(net 449 "AUX_JTAG_RST")
			(pintype "passive")
		)
	)
	(footprint "antmicro-footprints:R_0402_1005Metric"
		(layer "F.Cu")
		(at 142.536328 100.246157 90)
		(descr "Resistor SMD 0402")
		(tags "resistor SMD 0402")
		(property "Reference" "R22"
			(at 0.746157 0.388672 90)
			(layer "F.SilkS")
			(effects
				(font
					(size 0.7 0.7)
					(thickness 0.15)
				)
				(justify left bottom)
			)
		)
		(property "Value" "R_22R_0402"
			(at 0 1.4 90)
			(layer "F.Fab")
			(effects
				(font
					(size 0.7 0.7)
					(thickness 0.15)
				)
				(justify left bottom)
			)
		)
		(property "Description" "22R resistor in 0402 package with 1% tolerance"
			(at 0 0 90)
			(layer "F.Fab")
			(hide yes)
			(effects
				(font
					(size 1.27 1.27)
					(thickness 0.15)
				)
			)
		)
		(property "Author" "Antmicro"
			(at 242.782485 -42.290171 0)
			(layer "F.Fab")
			(hide yes)
			(effects
				(font
					(size 1 1)
					(thickness 0.15)
				)
			)
		)
		(property "License" "Apache-2.0"
			(at 242.782485 -42.290171 0)
			(layer "F.Fab")
			(hide yes)
			(effects
				(font
					(size 1 1)
					(thickness 0.15)
				)
			)
		)
		(property "MPN" "CR0402-FX-22R0GLF"
			(at 242.782485 -42.290171 0)
			(layer "F.Fab")
			(hide yes)
			(effects
				(font
					(size 1 1)
					(thickness 0.15)
				)
			)
		)
		(property "Manufacturer" "Bourns"
			(at 242.782485 -42.290171 0)
			(layer "F.Fab")
			(hide yes)
			(effects
				(font
					(size 1 1)
					(thickness 0.15)
				)
			)
		)
		(property "Tolerance" "1%"
			(at 242.782485 -42.290171 0)
			(layer "F.Fab")
			(hide yes)
			(effects
				(font
					(size 1 1)
					(thickness 0.15)
				)
			)
		)
		(property "Val" "22R"
			(at 242.782485 -42.290171 0)
			(layer "F.Fab")
			(hide yes)
			(effects
				(font
					(size 1 1)
					(thickness 0.15)
				)
			)
		)
		(sheetname "Interfaces")
		(sheetfile "interfaces.kicad_sch")
		(attr smd)
		(fp_rect
			(start -0.93 -0.47)
			(end 0.93 0.47)
			(stroke
				(width 0.05)
				(type solid)
			)
			(fill no)
			(layer "F.CrtYd")
		)
		(fp_rect
			(start -0.5 -0.25)
			(end 0.5 0.25)
			(stroke
				(width 0.15)
				(type solid)
			)
			(fill no)
			(layer "F.Fab")
		)
		(pad "1" smd roundrect
			(at -0.485 0 90)
			(size 0.59 0.64)
			(layers "F.Cu" "F.Mask" "F.Paste")
			(roundrect_rratio 0.25)
			(net 251 "Net-(U4-CDBUS0)")
			(pintype "passive")
		)
		(pad "2" smd roundrect
			(at 0.485 0 90)
			(size 0.59 0.64)
			(layers "F.Cu" "F.Mask" "F.Paste")
			(roundrect_rratio 0.25)
			(net 451 "UART0_RX")
			(pintype "passive")
		)
	)
)
